(kicad_pcb
	(version 20241229)
	(generator "pcbnew")
	(generator_version "9.0")
	(general
		(thickness 1.6)
		(legacy_teardrops no)
	)
	(paper "A4")
	(title_block
		(title "LPDDR4 testbed")
		(date "2024-03-26")
		(rev "1.2.2")
		(comment 9 "footprints 24-29 of 66")
	)
	(layers
		(0 "F.Cu" signal)
		(4 "In1.Cu" power)
		(6 "In2.Cu" power)
		(8 "In3.Cu" signal)
		(10 "In4.Cu" signal)
		(2 "B.Cu" signal)
		(9 "F.Adhes" user "F.Adhesive")
		(11 "B.Adhes" user "B.Adhesive")
		(13 "F.Paste" user)
		(15 "B.Paste" user)
		(5 "F.SilkS" user "F.Silkscreen")
		(7 "B.SilkS" user "B.Silkscreen")
		(1 "F.Mask" user)
		(3 "B.Mask" user)
		(17 "Dwgs.User" user "User.Drawings")
		(19 "Cmts.User" user "User.Comments")
		(21 "Eco1.User" user "User.Eco1")
		(23 "Eco2.User" user "User.Eco2")
		(25 "Edge.Cuts" user)
		(27 "Margin" user)
		(31 "F.CrtYd" user "F.Courtyard")
		(29 "B.CrtYd" user "B.Courtyard")
		(35 "F.Fab" user)
		(33 "B.Fab" user)
	)
	(footprint "antmicro-footprints:C_0201"
		(layer "F.Cu")
		(at 142.925 81.25 90)
		(descr "Capacitor SMD 0201")
		(tags "capacitor SMD 0201")
		(property "Reference" "C10"
			(at 0.2 -0.55 90)
			(layer "F.SilkS")
			(effects
				(font
					(size 0.7 0.7)
					(thickness 0.15)
				)
				(justify left bottom)
			)
		)
		(property "Value" "C_100n_0201"
			(at 0 1.4 90)
			(layer "F.Fab")
			(effects
				(font
					(size 0.7 0.7)
					(thickness 0.15)
				)
				(justify left bottom)
			)
		)
		(property "Description" " "
			(at 0 0 90)
			(layer "F.Fab")
			(hide yes)
			(effects
				(font
					(size 1.27 1.27)
					(thickness 0.15)
				)
			)
		)
		(property "Author" "Antmicro"
			(at 224.175 -61.675 0)
			(layer "F.Fab")
			(hide yes)
			(effects
				(font
					(size 1 1)
					(thickness 0.15)
				)
			)
		)
		(property "Dielectric" ""
			(at 224.175 -61.675 0)
			(layer "F.Fab")
			(hide yes)
			(effects
				(font
					(size 1 1)
					(thickness 0.15)
				)
			)
		)
		(property "License" "Apache-2.0"
			(at 224.175 -61.675 0)
			(layer "F.Fab")
			(hide yes)
			(effects
				(font
					(size 1 1)
					(thickness 0.15)
				)
			)
		)
		(property "MPN" "CC0201KRX6S5BB104"
			(at 224.175 -61.675 0)
			(layer "F.Fab")
			(hide yes)
			(effects
				(font
					(size 1 1)
					(thickness 0.15)
				)
			)
		)
		(property "Manufacturer" "YAGEO"
			(at 224.175 -61.675 0)
			(layer "F.Fab")
			(hide yes)
			(effects
				(font
					(size 1 1)
					(thickness 0.15)
				)
			)
		)
		(property "Val" "100n"
			(at 224.175 -61.675 0)
			(layer "F.Fab")
			(hide yes)
			(effects
				(font
					(size 1 1)
					(thickness 0.15)
				)
			)
		)
		(property "Voltage" ""
			(at 224.175 -61.675 0)
			(layer "F.Fab")
			(hide yes)
			(effects
				(font
					(size 1 1)
					(thickness 0.15)
				)
			)
		)
		(sheetname "LPDDR4")
		(sheetfile "lpddr4.kicad_sch")
		(attr smd)
		(fp_rect
			(start -0.72 -0.38)
			(end 0.72 0.38)
			(stroke
				(width 0.05)
				(type solid)
			)
			(fill no)
			(layer "F.CrtYd")
		)
		(fp_rect
			(start 0.3 0.15)
			(end -0.301 -0.149)
			(stroke
				(width 0.15)
				(type solid)
			)
			(fill no)
			(layer "F.Fab")
		)
		(pad "" smd roundrect
			(at -0.349 -0.002 90)
			(size 0.318 0.36)
			(layers "F.Paste")
			(roundrect_rratio 0.25)
		)
		(pad "" smd roundrect
			(at 0.341 -0.002 90)
			(size 0.318 0.36)
			(layers "F.Paste")
			(roundrect_rratio 0.25)
		)
		(pad "1" smd roundrect
			(at -0.321 -0.002 90)
			(size 0.46 0.4)
			(layers "F.Cu" "F.Mask")
			(roundrect_rratio 0.25)
			(net 36 "GND")
			(pintype "passive")
		)
		(pad "2" smd roundrect
			(at 0.32 -0.002 90)
			(size 0.46 0.4)
			(layers "F.Cu" "F.Mask")
			(roundrect_rratio 0.25)
			(net 189 "VDDQ")
			(pintype "passive")
		)
	)
	(footprint "antmicro-footprints:C_0201"
		(layer "F.Cu")
		(at 142.925 84.25 90)
		(descr "Capacitor SMD 0201")
		(tags "capacitor SMD 0201")
		(property "Reference" "C15"
			(at -1.4 -0.45 90)
			(layer "F.SilkS")
			(effects
				(font
					(size 0.7 0.7)
					(thickness 0.15)
				)
				(justify left bottom)
			)
		)
		(property "Value" "C_100n_0201"
			(at 0 1.4 90)
			(layer "F.Fab")
			(effects
				(font
					(size 0.7 0.7)
					(thickness 0.15)
				)
				(justify left bottom)
			)
		)
		(property "Description" " "
			(at 0 0 90)
			(layer "F.Fab")
			(hide yes)
			(effects
				(font
					(size 1.27 1.27)
					(thickness 0.15)
				)
			)
		)
		(property "Author" "Antmicro"
			(at 227.175 -58.675 0)
			(layer "F.Fab")
			(hide yes)
			(effects
				(font
					(size 1 1)
					(thickness 0.15)
				)
			)
		)
		(property "Dielectric" ""
			(at 227.175 -58.675 0)
			(layer "F.Fab")
			(hide yes)
			(effects
				(font
					(size 1 1)
					(thickness 0.15)
				)
			)
		)
		(property "License" "Apache-2.0"
			(at 227.175 -58.675 0)
			(layer "F.Fab")
			(hide yes)
			(effects
				(font
					(size 1 1)
					(thickness 0.15)
				)
			)
		)
		(property "MPN" "CC0201KRX6S5BB104"
			(at 227.175 -58.675 0)
			(layer "F.Fab")
			(hide yes)
			(effects
				(font
					(size 1 1)
					(thickness 0.15)
				)
			)
		)
		(property "Manufacturer" "YAGEO"
			(at 227.175 -58.675 0)
			(layer "F.Fab")
			(hide yes)
			(effects
				(font
					(size 1 1)
					(thickness 0.15)
				)
			)
		)
		(property "Val" "100n"
			(at 227.175 -58.675 0)
			(layer "F.Fab")
			(hide yes)
			(effects
				(font
					(size 1 1)
					(thickness 0.15)
				)
			)
		)
		(property "Voltage" ""
			(at 227.175 -58.675 0)
			(layer "F.Fab")
			(hide yes)
			(effects
				(font
					(size 1 1)
					(thickness 0.15)
				)
			)
		)
		(sheetname "LPDDR4")
		(sheetfile "lpddr4.kicad_sch")
		(attr smd)
		(fp_rect
			(start -0.72 -0.38)
			(end 0.72 0.38)
			(stroke
				(width 0.05)
				(type solid)
			)
			(fill no)
			(layer "F.CrtYd")
		)
		(fp_rect
			(start 0.3 0.15)
			(end -0.301 -0.149)
			(stroke
				(width 0.15)
				(type solid)
			)
			(fill no)
			(layer "F.Fab")
		)
		(pad "" smd roundrect
			(at -0.349 -0.002 90)
			(size 0.318 0.36)
			(layers "F.Paste")
			(roundrect_rratio 0.25)
		)
		(pad "" smd roundrect
			(at 0.341 -0.002 90)
			(size 0.318 0.36)
			(layers "F.Paste")
			(roundrect_rratio 0.25)
		)
		(pad "1" smd roundrect
			(at -0.321 -0.002 90)
			(size 0.46 0.4)
			(layers "F.Cu" "F.Mask")
			(roundrect_rratio 0.25)
			(net 36 "GND")
			(pintype "passive")
		)
		(pad "2" smd roundrect
			(at 0.32 -0.002 90)
			(size 0.46 0.4)
			(layers "F.Cu" "F.Mask")
			(roundrect_rratio 0.25)
			(net 188 "VDD2")
			(pintype "passive")
		)
	)
	(footprint "antmicro-footprints:C_0402_1005Metric"
		(layer "F.Cu")
		(at 134.175 85.2 -90)
		(descr "Capacitor SMD 0402")
		(tags "capacitor SMD 0402")
		(property "Reference" "C34"
			(at -1.05 -1.4 90)
			(layer "F.SilkS")
			(effects
				(font
					(size 0.7 0.7)
					(thickness 0.15)
				)
				(justify right bottom)
			)
		)
		(property "Value" "C_4u7_0402"
			(at 0 1.4 90)
			(layer "F.Fab")
			(effects
				(font
					(size 0.7 0.7)
					(thickness 0.15)
				)
				(justify right bottom)
			)
		)
		(property "Description" " "
			(at 0 0 270)
			(layer "F.Fab")
			(hide yes)
			(effects
				(font
					(size 1.27 1.27)
					(thickness 0.15)
				)
			)
		)
		(property "Author" "Antmicro"
			(at 48.975 219.375 0)
			(layer "F.Fab")
			(hide yes)
			(effects
				(font
					(size 1 1)
					(thickness 0.15)
				)
			)
		)
		(property "Dielectric" ""
			(at 48.975 219.375 0)
			(layer "F.Fab")
			(hide yes)
			(effects
				(font
					(size 1 1)
					(thickness 0.15)
				)
			)
		)
		(property "License" "Apache-2.0"
			(at 48.975 219.375 0)
			(layer "F.Fab")
			(hide yes)
			(effects
				(font
					(size 1 1)
					(thickness 0.15)
				)
			)
		)
		(property "MPN" "GRM155R61A475MEAAD"
			(at 48.975 219.375 0)
			(layer "F.Fab")
			(hide yes)
			(effects
				(font
					(size 1 1)
					(thickness 0.15)
				)
			)
		)
		(property "Manufacturer" "Murata"
			(at 48.975 219.375 0)
			(layer "F.Fab")
			(hide yes)
			(effects
				(font
					(size 1 1)
					(thickness 0.15)
				)
			)
		)
		(property "Val" "4u7"
			(at 48.975 219.375 0)
			(layer "F.Fab")
			(hide yes)
			(effects
				(font
					(size 1 1)
					(thickness 0.15)
				)
			)
		)
		(property "Voltage" ""
			(at 48.975 219.375 0)
			(layer "F.Fab")
			(hide yes)
			(effects
				(font
					(size 1 1)
					(thickness 0.15)
				)
			)
		)
		(sheetname "EEPROM")
		(sheetfile "EEPROM.kicad_sch")
		(attr smd)
		(fp_rect
			(start -0.94 -0.47)
			(end 0.94 0.47)
			(stroke
				(width 0.05)
				(type solid)
			)
			(fill no)
			(layer "F.CrtYd")
		)
		(fp_rect
			(start -0.499 -0.249)
			(end 0.499 0.249)
			(stroke
				(width 0.15)
				(type solid)
			)
			(fill no)
			(layer "F.Fab")
		)
		(pad "1" smd roundrect
			(at -0.484 0 270)
			(size 0.59 0.64)
			(layers "F.Cu" "F.Mask" "F.Paste")
			(roundrect_rratio 0.25)
			(net 36 "GND")
			(pintype "passive")
		)
		(pad "2" smd roundrect
			(at 0.484 0 270)
			(size 0.59 0.64)
			(layers "F.Cu" "F.Mask" "F.Paste")
			(roundrect_rratio 0.25)
			(net 187 "VDD1")
			(pintype "passive")
		)
	)
	(footprint "antmicro-footprints:C_0402_1005Metric"
		(layer "F.Cu")
		(at 130.66 81.15 180)
		(descr "Capacitor SMD 0402")
		(tags "capacitor SMD 0402")
		(property "Reference" "C37"
			(at -0.915 0.6 0)
			(layer "F.SilkS")
			(effects
				(font
					(size 0.7 0.7)
					(thickness 0.15)
				)
				(justify right bottom)
			)
		)
		(property "Value" "C_4u7_0402"
			(at 0 1.4 0)
			(layer "F.Fab")
			(effects
				(font
					(size 0.7 0.7)
					(thickness 0.15)
				)
				(justify right bottom)
			)
		)
		(property "Description" " "
			(at 0 0 180)
			(layer "F.Fab")
			(hide yes)
			(effects
				(font
					(size 1.27 1.27)
					(thickness 0.15)
				)
			)
		)
		(property "Author" "Antmicro"
			(at 261.32 162.3 0)
			(layer "F.Fab")
			(hide yes)
			(effects
				(font
					(size 1 1)
					(thickness 0.15)
				)
			)
		)
		(property "License" "Apache-2.0"
			(at 261.32 162.3 0)
			(layer "F.Fab")
			(hide yes)
			(effects
				(font
					(size 1 1)
					(thickness 0.15)
				)
			)
		)
		(property "MPN" "GRM155R61A475MEAAD"
			(at 261.32 162.3 0)
			(layer "F.Fab")
			(hide yes)
			(effects
				(font
					(size 1 1)
					(thickness 0.15)
				)
			)
		)
		(property "Manufacturer" "Murata"
			(at 261.32 162.3 0)
			(layer "F.Fab")
			(hide yes)
			(effects
				(font
					(size 1 1)
					(thickness 0.15)
				)
			)
		)
		(property "Val" "4u7"
			(at 261.32 162.3 0)
			(layer "F.Fab")
			(hide yes)
			(effects
				(font
					(size 1 1)
					(thickness 0.15)
				)
			)
		)
		(sheetname "EEPROM")
		(sheetfile "EEPROM.kicad_sch")
		(attr smd)
		(fp_rect
			(start -0.94 -0.47)
			(end 0.94 0.47)
			(stroke
				(width 0.05)
				(type solid)
			)
			(fill no)
			(layer "F.CrtYd")
		)
		(fp_rect
			(start -0.499 -0.249)
			(end 0.499 0.249)
			(stroke
				(width 0.15)
				(type solid)
			)
			(fill no)
			(layer "F.Fab")
		)
		(pad "1" smd roundrect
			(at -0.484 0 180)
			(size 0.59 0.64)
			(layers "F.Cu" "F.Mask" "F.Paste")
			(roundrect_rratio 0.25)
			(net 36 "GND")
			(pintype "passive")
		)
		(pad "2" smd roundrect
			(at 0.484 0 180)
			(size 0.59 0.64)
			(layers "F.Cu" "F.Mask" "F.Paste")
			(roundrect_rratio 0.25)
			(net 241 "VDDLED")
			(pintype "passive")
		)
	)
	(footprint "antmicro-footprints:C_0402_1005Metric"
		(layer "F.Cu")
		(at 122.76 81.545 180)
		(descr "Capacitor SMD 0402")
		(tags "capacitor SMD 0402")
		(property "Reference" "C38"
			(at -1.015 0.595 0)
			(layer "F.SilkS")
			(effects
				(font
					(size 0.7 0.7)
					(thickness 0.15)
				)
				(justify right bottom)
			)
		)
		(property "Value" "C_100n_0402"
			(at 0 1.4 0)
			(layer "F.Fab")
			(effects
				(font
					(size 0.7 0.7)
					(thickness 0.15)
				)
				(justify right bottom)
			)
		)
		(property "Description" " "
			(at 0 0 180)
			(layer "F.Fab")
			(hide yes)
			(effects
				(font
					(size 1.27 1.27)
					(thickness 0.15)
				)
			)
		)
		(property "Author" "Antmicro"
			(at 245.52 163.09 0)
			(layer "F.Fab")
			(hide yes)
			(effects
				(font
					(size 1 1)
					(thickness 0.15)
				)
			)
		)
		(property "Dielectric" "X5R"
			(at 245.52 163.09 0)
			(layer "F.Fab")
			(hide yes)
			(effects
				(font
					(size 1 1)
					(thickness 0.15)
				)
			)
		)
		(property "License" "Apache-2.0"
			(at 245.52 163.09 0)
			(layer "F.Fab")
			(hide yes)
			(effects
				(font
					(size 1 1)
					(thickness 0.15)
				)
			)
		)
		(property "MPN" "0402X104K6R3CT"
			(at 245.52 163.09 0)
			(layer "F.Fab")
			(hide yes)
			(effects
				(font
					(size 1 1)
					(thickness 0.15)
				)
			)
		)
		(property "Manufacturer" "Walsin"
			(at 245.52 163.09 0)
			(layer "F.Fab")
			(hide yes)
			(effects
				(font
					(size 1 1)
					(thickness 0.15)
				)
			)
		)
		(property "Val" "100n"
			(at 245.52 163.09 0)
			(layer "F.Fab")
			(hide yes)
			(effects
				(font
					(size 1 1)
					(thickness 0.15)
				)
			)
		)
		(property "Voltage" "50V"
			(at 245.52 163.09 0)
			(layer "F.Fab")
			(hide yes)
			(effects
				(font
					(size 1 1)
					(thickness 0.15)
				)
			)
		)
		(sheetname "EEPROM")
		(sheetfile "EEPROM.kicad_sch")
		(attr smd)
		(fp_rect
			(start -0.94 -0.47)
			(end 0.94 0.47)
			(stroke
				(width 0.05)
				(type solid)
			)
			(fill no)
			(layer "F.CrtYd")
		)
		(fp_rect
			(start -0.499 -0.249)
			(end 0.499 0.249)
			(stroke
				(width 0.15)
				(type solid)
			)
			(fill no)
			(layer "F.Fab")
		)
		(pad "1" smd roundrect
			(at -0.484 0 180)
			(size 0.59 0.64)
			(layers "F.Cu" "F.Mask" "F.Paste")
			(roundrect_rratio 0.25)
			(net 36 "GND")
			(pintype "passive")
		)
		(pad "2" smd roundrect
			(at 0.484 0 180)
			(size 0.59 0.64)
			(layers "F.Cu" "F.Mask" "F.Paste")
			(roundrect_rratio 0.25)
			(net 187 "VDD1")
			(pintype "passive")
		)
	)
	(footprint "antmicro-footprints:LED_0603_1608Metric_G"
		(layer "F.Cu")
		(at 133.075 72.9 90)
		(descr "LED SMD 0603 Green")
		(tags "LED SMD 0603 Green")
		(property "Reference" "D4"
			(at 1.25 0.32 90)
			(layer "F.SilkS")
			(effects
				(font
					(size 0.7 0.7)
					(thickness 0.15)
				)
				(justify left bottom)
			)
		)
		(property "Value" "LED_G_0603_KP-1608CGCK"
			(at 0 1.6 90)
			(layer "F.Fab")
			(effects
				(font
					(size 0.7 0.7)
					(thickness 0.15)
				)
				(justify left bottom)
			)
		)
		(property "Author" "Antmicro"
			(at 205.975 -60.175 0)
			(layer "F.Fab")
			(hide yes)
			(effects
				(font
					(size 1 1)
					(thickness 0.15)
				)
			)
		)
		(property "License" "Apache-2.0"
			(at 205.975 -60.175 0)
			(layer "F.Fab")
			(hide yes)
			(effects
				(font
					(size 1 1)
					(thickness 0.15)
				)
			)
		)
		(property "MPN" "KP-1608CGCK"
			(at 205.975 -60.175 0)
			(layer "F.Fab")
			(hide yes)
			(effects
				(font
					(size 1 1)
					(thickness 0.15)
				)
			)
		)
		(property "Manufacturer" "Kingbright"
			(at 205.975 -60.175 0)
			(layer "F.Fab")
			(hide yes)
			(effects
				(font
					(size 1 1)
					(thickness 0.15)
				)
			)
		)
		(sheetname "EEPROM")
		(sheetfile "EEPROM.kicad_sch")
		(attr smd)
		(fp_line
			(start -0.27 -0.35)
			(end 0.27 -0.35)
			(stroke
				(width 0.15)
				(type solid)
			)
			(layer "F.SilkS")
		)
		(fp_line
			(start 0.093672 -0.200008)
			(end 0.093672 0.199992)
			(stroke
				(width 0.1)
				(type solid)
			)
			(layer "F.SilkS")
		)
		(fp_line
			(start -0.106328 -0.200008)
			(end 0.093672 -8e-06)
			(stroke
				(width 0.1)
				(type solid)
			)
			(layer "F.SilkS")
		)
		(fp_line
			(start -0.106328 -0.200008)
			(end -0.106328 0.199992)
			(stroke
				(width 0.1)
				(type solid)
			)
			(layer "F.SilkS")
		)
		(fp_line
			(start 0.093672 -8e-06)
			(end 0.293672 -8e-06)
			(stroke
				(width 0.1)
				(type solid)
			)
			(layer "F.SilkS")
		)
		(fp_line
			(start 0.093672 -8e-06)
			(end -0.106328 0.199992)
			(stroke
				(width 0.1)
				(type solid)
			)
			(layer "F.SilkS")
		)
		(fp_line
			(start -0.106328 -8e-06)
			(end -0.29 0)
			(stroke
				(width 0.1)
				(type solid)
			)
			(layer "F.SilkS")
		)
		(fp_line
			(start 1.25 0.32)
			(end 1.25 -0.32)
			(stroke
				(width 0.15)
				(type solid)
			)
			(layer "F.SilkS")
		)
		(fp_line
			(start -0.27 0.351)
			(end 0.27 0.351)
			(stroke
				(width 0.15)
				(type solid)
			)
			(layer "F.SilkS")
		)
		(fp_rect
			(start 1.26 0.65)
			(end -1.26 -0.65)
			(stroke
				(width 0.05)
				(type solid)
			)
			(fill no)
			(layer "F.CrtYd")
		)
		(fp_line
			(start 0.199 -0.2)
			(end 0.199 -0.1)
			(stroke
				(width 0.15)
				(type solid)
			)
			(layer "F.Fab")
		)
		(fp_line
			(start -0.201 -0.2)
			(end -0.201 0)
			(stroke
				(width 0.15)
				(type solid)
			)
			(layer "F.Fab")
		)
		(fp_line
			(start 0.199 0)
			(end 0.597 0)
			(stroke
				(width 0.15)
				(type solid)
			)
			(layer "F.Fab")
		)
		(fp_line
			(start 0.101 0)
			(end -0.201 -0.2)
			(stroke
				(width 0.15)
				(type solid)
			)
			(layer "F.Fab")
		)
		(fp_line
			(start -0.201 0)
			(end -0.201 0.202)
			(stroke
				(width 0.15)
				(type solid)
			)
			(layer "F.Fab")
		)
		(fp_line
			(start -0.599 0)
			(end -0.201 0)
			(stroke
				(width 0.15)
				(type solid)
			)
			(layer "F.Fab")
		)
		(fp_line
			(start 0.199 0.202)
			(end 0.199 -0.1)
			(stroke
				(width 0.15)
				(type solid)
			)
			(layer "F.Fab")
		)
		(fp_line
			(start -0.201 0.202)
			(end 0.101 0)
			(stroke
				(width 0.15)
				(type solid)
			)
			(layer "F.Fab")
		)
		(fp_rect
			(start -0.848 -0.4)
			(end 0.85 0.402)
			(stroke
				(width 0.15)
				(type solid)
			)
			(fill no)
			(layer "F.Fab")
		)
		(pad "1" smd rect
			(at -0.75 0 270)
			(size 0.8 0.8)
			(layers "F.Cu" "F.Mask" "F.Paste")
			(net 258 "Net-(D4-Pad1)")
			(pinfunction "1")
			(pintype "passive")
		)
		(pad "2" smd rect
			(at 0.75 0 270)
			(size 0.8 0.8)
			(layers "F.Cu" "F.Mask" "F.Paste")
			(net 36 "GND")
			(pinfunction "2")
			(pintype "passive")
		)
	)
)
